(kicad_pcb
	(version 20260206)
	(generator "pcbnew")
	(generator_version "10.0")
	(general
		(thickness 1.6)
		(legacy_teardrops no)
	)
	(paper "A4")
	(title_block
		(title "timecard-production-celestica-r4006 — R4006-B0001-02_R01.brd")
		(comment 1 "Time Appliance Project (Time Card) / footprints 1039-1043 of 1113")
	)
	(layers
		(0 "F.Cu" signal "TOP")
		(4 "In1.Cu" signal "L02_GND1")
		(6 "In2.Cu" signal "L03_SIG1")
		(8 "In3.Cu" signal "L04_GND2")
		(10 "In4.Cu" signal "L05_VCC1")
		(12 "In5.Cu" signal "L06_VCC2")
		(14 "In6.Cu" signal "L07_GND3")
		(16 "In7.Cu" signal "L08_SIG2")
		(18 "In8.Cu" signal "L09_GND4")
		(2 "B.Cu" signal "BOTTOM")
		(9 "F.Adhes" user "F.Adhesive")
		(11 "B.Adhes" user "B.Adhesive")
		(13 "F.Paste" user "Package Geometry/Pastemask Top")
		(15 "B.Paste" user "Package Geometry/Pastemask Bottom")
		(5 "F.SilkS" user "Ref Des/Silkscreen Top")
		(7 "B.SilkS" user "Ref Des/Silkscreen Bottom")
		(1 "F.Mask" user "Board Geometry/Soldermask Top")
		(3 "B.Mask" user "Board Geometry/Soldermask Bottom")
		(17 "Dwgs.User" user "User.Drawings")
		(19 "Cmts.User" user "User.Comments")
		(21 "Eco1.User" user "User.Eco1")
		(23 "Eco2.User" user "User.Eco2")
		(25 "Edge.Cuts" user "Board Geometry/Outline")
		(27 "Margin" user)
		(31 "F.CrtYd" user "Package Geometry/Place Bound Top")
		(29 "B.CrtYd" user "Package Geometry/Place Bound Bottom")
		(35 "F.Fab" user "Ref Des/Assembly Top")
		(33 "B.Fab" user "Ref Des/Assembly Bottom")
	)
	(footprint ""
		(layer "B.Cu")
		(at 83.2358 -84.836 180)
		(property "Reference" "R150"
			(at 0.6858 5.67563 0)
			(unlocked yes)
			(layer "B.SilkS")
			(effects
				(font
					(size 0.7874 0.5842)
					(thickness 0.1524)
				)
				(justify mirror)
			)
		)
		(property "Value" "VAL*"
			(at -0.02032 2.13233 180)
			(unlocked yes)
			(layer "B.Fab")
			(hide yes)
			(effects
				(font
					(size 0.7874 0.5842)
					(thickness 0.1524)
				)
				(justify mirror)
			)
		)
		(property "Tolerance" "TOL*"
			(at -0.044704 3.05435 180)
			(unlocked yes)
			(layer "Cmts.User")
			(hide yes)
			(effects
				(font
					(size 0.7874 0.5842)
					(thickness 0.1524)
				)
				(justify mirror)
			)
		)
		(property "User Part Number" "PARTNUM*"
			(at -0.02032 4.024884 180)
			(unlocked yes)
			(layer "Cmts.User")
			(hide yes)
			(effects
				(font
					(size 0.7874 0.5842)
					(thickness 0.1524)
				)
				(justify mirror)
			)
		)
		(property "Device Type" "RESISTOR-G155-14701-01,4.7KOHMA"
			(at -0.008382 1.210564 180)
			(unlocked yes)
			(layer "B.Fab")
			(hide yes)
			(effects
				(font
					(size 0.7874 0.5842)
					(thickness 0.1524)
				)
				(justify mirror)
			)
		)
		(duplicate_pad_numbers_are_jumpers no)
		(fp_line
			(start 1.143 0.5588)
			(end -1.143 0.5588)
			(stroke
				(width 0.1)
				(type default)
			)
			(layer "B.SilkS")
		)
		(fp_line
			(start 1.143 -0.5588)
			(end 1.143 0.5588)
			(stroke
				(width 0.1)
				(type default)
			)
			(layer "B.SilkS")
		)
		(fp_line
			(start -1.143 0.5588)
			(end -1.143 -0.5588)
			(stroke
				(width 0.1)
				(type default)
			)
			(layer "B.SilkS")
		)
		(fp_line
			(start -1.143 -0.5588)
			(end 1.143 -0.5588)
			(stroke
				(width 0.1)
				(type default)
			)
			(layer "B.SilkS")
		)
		(fp_rect
			(start -1.143 0.5588)
			(end 1.143 -0.5588)
			(stroke
				(width 0)
				(type default)
			)
			(fill no)
			(layer "B.CrtYd")
		)
		(fp_line
			(start 0.508 0.3048)
			(end -0.508 0.3048)
			(stroke
				(width 0.1)
				(type default)
			)
			(layer "B.Fab")
		)
		(fp_line
			(start 0.508 -0.3048)
			(end 0.508 0.3048)
			(stroke
				(width 0.1)
				(type default)
			)
			(layer "B.Fab")
		)
		(fp_line
			(start -0.508 0.3048)
			(end -0.508 -0.3048)
			(stroke
				(width 0.1)
				(type default)
			)
			(layer "B.Fab")
		)
		(fp_line
			(start -0.508 -0.3048)
			(end 0.508 -0.3048)
			(stroke
				(width 0.1)
				(type default)
			)
			(layer "B.Fab")
		)
		(pad "1" smd rect
			(at 0.5334 0)
			(size 0.7112 0.6096)
			(layers "B.Cu" "B.Mask" "B.Paste")
			(net "XP3R3V_FPGA")
		)
		(pad "2" smd rect
			(at -0.5334 0)
			(size 0.7112 0.6096)
			(layers "B.Cu" "B.Mask" "B.Paste")
			(net "UNNAMED_5_PCA9546APWTSSOP16_I_1")
		)
		(zone
			(layer "B.Cu")
			(hatch none 0.5)
			(connect_pads
				(clearance 0)
			)
			(min_thickness 0.25)
			(keepout
				(tracks allowed)
				(vias not_allowed)
				(pads allowed)
				(copperpour not_allowed)
				(footprints allowed)
			)
			(placement
				(enabled no)
				(sheetname "")
			)
			(fill
				(thermal_gap 0.5)
				(thermal_bridge_width 0.5)
				(island_removal_mode 0)
			)
			(polygon
				(pts
					(xy 83.312 -85.1408) (xy 83.1596 -85.1408) (xy 83.1596 -84.5312) (xy 83.312 -84.5312)
				)
			)
		)
	)
	(footprint ""
		(layer "B.Cu")
		(at 108.966 -18.542 180)
		(property "Reference" "C244"
			(at 0 -1.30937 0)
			(unlocked yes)
			(layer "B.SilkS")
			(effects
				(font
					(size 0.7874 0.5842)
					(thickness 0.1524)
				)
				(justify mirror)
			)
		)
		(property "Value" "VAL*"
			(at -0.0762 2.067306 180)
			(unlocked yes)
			(layer "B.Fab")
			(hide yes)
			(effects
				(font
					(size 0.7874 0.5842)
					(thickness 0.1524)
				)
				(justify mirror)
			)
		)
		(property "Device Type" "CAPACITOR-G105-0B104-EK,0.1UF,A"
			(at -0.0508 1.127506 180)
			(unlocked yes)
			(layer "B.Fab")
			(hide yes)
			(effects
				(font
					(size 0.7874 0.5842)
					(thickness 0.1524)
				)
				(justify mirror)
			)
		)
		(property "User Part Number" "PARTNUM*"
			(at -0.1016 4.023106 180)
			(unlocked yes)
			(layer "Cmts.User")
			(hide yes)
			(effects
				(font
					(size 0.7874 0.5842)
					(thickness 0.1524)
				)
				(justify mirror)
			)
		)
		(property "Tolerance" "TOL*"
			(at -0.0762 3.032506 180)
			(unlocked yes)
			(layer "Cmts.User")
			(hide yes)
			(effects
				(font
					(size 0.7874 0.5842)
					(thickness 0.1524)
				)
				(justify mirror)
			)
		)
		(duplicate_pad_numbers_are_jumpers no)
		(fp_line
			(start 1.143 0.5588)
			(end -1.143 0.5588)
			(stroke
				(width 0.1)
				(type default)
			)
			(layer "B.SilkS")
		)
		(fp_line
			(start 1.143 -0.5588)
			(end 1.143 0.5588)
			(stroke
				(width 0.1)
				(type default)
			)
			(layer "B.SilkS")
		)
		(fp_line
			(start -1.143 0.5588)
			(end -1.143 -0.5588)
			(stroke
				(width 0.1)
				(type default)
			)
			(layer "B.SilkS")
		)
		(fp_line
			(start -1.143 -0.5588)
			(end 1.143 -0.5588)
			(stroke
				(width 0.1)
				(type default)
			)
			(layer "B.SilkS")
		)
		(fp_rect
			(start 1.143 -0.5588)
			(end -1.143 0.5588)
			(stroke
				(width 0)
				(type default)
			)
			(fill no)
			(layer "B.CrtYd")
		)
		(fp_line
			(start 0.508 0.3048)
			(end -0.508 0.3048)
			(stroke
				(width 0.1)
				(type default)
			)
			(layer "B.Fab")
		)
		(fp_line
			(start 0.508 -0.3048)
			(end 0.508 0.3048)
			(stroke
				(width 0.1)
				(type default)
			)
			(layer "B.Fab")
		)
		(fp_line
			(start -0.508 0.3048)
			(end -0.508 -0.3048)
			(stroke
				(width 0.1)
				(type default)
			)
			(layer "B.Fab")
		)
		(fp_line
			(start -0.508 -0.3048)
			(end 0.508 -0.3048)
			(stroke
				(width 0.1)
				(type default)
			)
			(layer "B.Fab")
		)
		(pad "1" smd rect
			(at 0.5334 0)
			(size 0.7112 0.6096)
			(layers "B.Cu" "B.Mask" "B.Paste")
			(net "XP3R3V")
		)
		(pad "2" smd rect
			(at -0.5334 0)
			(size 0.7112 0.6096)
			(layers "B.Cu" "B.Mask" "B.Paste")
			(net "SG")
		)
		(zone
			(layer "B.Cu")
			(hatch none 0.5)
			(connect_pads
				(clearance 0)
			)
			(min_thickness 0.25)
			(keepout
				(tracks allowed)
				(vias not_allowed)
				(pads allowed)
				(copperpour not_allowed)
				(footprints allowed)
			)
			(placement
				(enabled no)
				(sheetname "")
			)
			(fill
				(thermal_gap 0.5)
				(thermal_bridge_width 0.5)
				(island_removal_mode 0)
			)
			(polygon
				(pts
					(xy 108.8898 -18.2372) (xy 109.0422 -18.2372) (xy 109.0422 -18.8468) (xy 108.8898 -18.8468)
				)
			)
		)
	)
	(footprint ""
		(layer "B.Cu")
		(at 67.514978 -15.367 -90)
		(property "Reference" "C26"
			(at 3.048 0.236728 270)
			(unlocked yes)
			(layer "B.SilkS")
			(effects
				(font
					(size 0.635 0.4064)
					(thickness 0.1524)
				)
				(justify mirror)
			)
		)
		(property "Value" "VAL*"
			(at -0.0762 2.067306 270)
			(unlocked yes)
			(layer "B.Fab")
			(hide yes)
			(effects
				(font
					(size 0.7874 0.5842)
					(thickness 0.1524)
				)
				(justify mirror)
			)
		)
		(property "Tolerance" "TOL*"
			(at -0.0762 3.032506 270)
			(unlocked yes)
			(layer "Cmts.User")
			(hide yes)
			(effects
				(font
					(size 0.7874 0.5842)
					(thickness 0.1524)
				)
				(justify mirror)
			)
		)
		(property "User Part Number" "PARTNUM*"
			(at -0.1016 4.023106 270)
			(unlocked yes)
			(layer "Cmts.User")
			(hide yes)
			(effects
				(font
					(size 0.7874 0.5842)
					(thickness 0.1524)
				)
				(justify mirror)
			)
		)
		(property "Device Type" "CAPACITOR-G105-0B104-CK,0.1UF,A"
			(at -0.0508 1.127506 270)
			(unlocked yes)
			(layer "B.Fab")
			(hide yes)
			(effects
				(font
					(size 0.7874 0.5842)
					(thickness 0.1524)
				)
				(justify mirror)
			)
		)
		(duplicate_pad_numbers_are_jumpers no)
		(fp_line
			(start -1.143 0.5588)
			(end -1.143 -0.5588)
			(stroke
				(width 0.1)
				(type default)
			)
			(layer "B.SilkS")
		)
		(fp_line
			(start 1.143 0.5588)
			(end -1.143 0.5588)
			(stroke
				(width 0.1)
				(type default)
			)
			(layer "B.SilkS")
		)
		(fp_line
			(start -1.143 -0.5588)
			(end 1.143 -0.5588)
			(stroke
				(width 0.1)
				(type default)
			)
			(layer "B.SilkS")
		)
		(fp_line
			(start 1.143 -0.5588)
			(end 1.143 0.5588)
			(stroke
				(width 0.1)
				(type default)
			)
			(layer "B.SilkS")
		)
		(fp_rect
			(start 1.143 0.5588)
			(end -1.143 -0.5588)
			(stroke
				(width 0)
				(type default)
			)
			(fill no)
			(layer "B.CrtYd")
		)
		(fp_line
			(start -0.508 0.3048)
			(end -0.508 -0.3048)
			(stroke
				(width 0.1)
				(type default)
			)
			(layer "B.Fab")
		)
		(fp_line
			(start 0.508 0.3048)
			(end -0.508 0.3048)
			(stroke
				(width 0.1)
				(type default)
			)
			(layer "B.Fab")
		)
		(fp_line
			(start -0.508 -0.3048)
			(end 0.508 -0.3048)
			(stroke
				(width 0.1)
				(type default)
			)
			(layer "B.Fab")
		)
		(fp_line
			(start 0.508 -0.3048)
			(end 0.508 0.3048)
			(stroke
				(width 0.1)
				(type default)
			)
			(layer "B.Fab")
		)
		(pad "1" smd rect
			(at 0.5334 0 90)
			(size 0.7112 0.6096)
			(layers "B.Cu" "B.Mask" "B.Paste")
			(net "C_CPU_RX_PCIE_MGT1_TXP")
		)
		(pad "2" smd rect
			(at -0.5334 0 90)
			(size 0.7112 0.6096)
			(layers "B.Cu" "B.Mask" "B.Paste")
			(net "CPU_RX_PCIE_MGT1_TXP")
		)
		(zone
			(layer "B.Cu")
			(hatch none 0.5)
			(connect_pads
				(clearance 0)
			)
			(min_thickness 0.25)
			(keepout
				(tracks allowed)
				(vias not_allowed)
				(pads allowed)
				(copperpour not_allowed)
				(footprints allowed)
			)
			(placement
				(enabled no)
				(sheetname "")
			)
			(fill
				(thermal_gap 0.5)
				(thermal_bridge_width 0.5)
				(island_removal_mode 0)
			)
			(polygon
				(pts
					(xy 67.210178 -15.2908) (xy 67.819778 -15.2908) (xy 67.819778 -15.4432) (xy 67.210178 -15.4432)
				)
			)
		)
	)
	(footprint ""
		(layer "B.Cu")
		(at 119.347234 -52.82311 180)
		(property "Reference" "R503"
			(at 2.253234 -0.02286 0)
			(unlocked yes)
			(layer "B.SilkS")
			(effects
				(font
					(size 0.635 0.4064)
					(thickness 0.1524)
				)
				(justify mirror)
			)
		)
		(property "Value" "VAL*"
			(at 0 3.718306 180)
			(unlocked yes)
			(layer "B.Fab")
			(hide yes)
			(effects
				(font
					(size 0.7874 0.5842)
					(thickness 0.127)
				)
				(justify mirror)
			)
		)
		(property "Tolerance" "TOL*"
			(at 0 4.861306 180)
			(unlocked yes)
			(layer "Cmts.User")
			(hide yes)
			(effects
				(font
					(size 0.7874 0.5842)
					(thickness 0.127)
				)
				(justify mirror)
			)
		)
		(property "User Part Number" "PARTNUM*"
			(at 0 2.575306 180)
			(unlocked yes)
			(layer "Cmts.User")
			(hide yes)
			(effects
				(font
					(size 0.7874 0.5842)
					(thickness 0.127)
				)
				(justify mirror)
			)
		)
		(property "Device Type" "RESISTOR-G155-14701-01,4.7KOHMA"
			(at 0 1.432306 180)
			(unlocked yes)
			(layer "B.Fab")
			(hide yes)
			(effects
				(font
					(size 0.7874 0.5842)
					(thickness 0.127)
				)
				(justify mirror)
			)
		)
		(duplicate_pad_numbers_are_jumpers no)
		(fp_line
			(start 0.970026 0.4699)
			(end 0.970026 -0.4699)
			(stroke
				(width 0.1)
				(type default)
			)
			(layer "B.SilkS")
		)
		(fp_line
			(start 0.970026 -0.4699)
			(end -0.970026 -0.4699)
			(stroke
				(width 0.1)
				(type default)
			)
			(layer "B.SilkS")
		)
		(fp_line
			(start -0.970026 0.4699)
			(end 0.970026 0.4699)
			(stroke
				(width 0.1)
				(type default)
			)
			(layer "B.SilkS")
		)
		(fp_line
			(start -0.970026 -0.4699)
			(end -0.970026 0.4699)
			(stroke
				(width 0.1)
				(type default)
			)
			(layer "B.SilkS")
		)
		(fp_poly
			(pts
				(xy 0.970026 0.4699) (xy -0.970026 0.4699) (xy -0.970026 -0.4699) (xy 0.970026 -0.4699)
			)
			(stroke
				(width 0)
				(type default)
			)
			(fill no)
			(layer "B.CrtYd")
		)
		(fp_line
			(start 0.508 0.3048)
			(end 0.508 -0.3048)
			(stroke
				(width 0.1)
				(type default)
			)
			(layer "B.Fab")
		)
		(fp_line
			(start 0.508 -0.3048)
			(end -0.508 -0.3048)
			(stroke
				(width 0.1)
				(type default)
			)
			(layer "B.Fab")
		)
		(fp_line
			(start -0.508 0.3048)
			(end 0.508 0.3048)
			(stroke
				(width 0.1)
				(type default)
			)
			(layer "B.Fab")
		)
		(fp_line
			(start -0.508 -0.3048)
			(end -0.508 0.3048)
			(stroke
				(width 0.1)
				(type default)
			)
			(layer "B.Fab")
		)
		(pad "1" smd circle
			(at 0.500126 0)
			(size 0.635 0.635)
			(layers "B.Cu" "B.Mask" "B.Paste")
			(net "ANT2_IN")
		)
		(pad "2" smd circle
			(at -0.500126 0)
			(size 0.635 0.635)
			(layers "B.Cu" "B.Mask" "B.Paste")
			(net "SG")
		)
	)
	(footprint ""
		(layer "B.Cu")
		(at 88.519 -73.279 90)
		(property "Reference" "R341"
			(at -3.556 -0.16637 270)
			(unlocked yes)
			(layer "B.SilkS")
			(effects
				(font
					(size 0.7874 0.5842)
					(thickness 0.1524)
				)
				(justify mirror)
			)
		)
		(property "Value" "VAL*"
			(at -0.02032 2.13233 90)
			(unlocked yes)
			(layer "B.Fab")
			(hide yes)
			(effects
				(font
					(size 0.7874 0.5842)
					(thickness 0.1524)
				)
				(justify mirror)
			)
		)
		(property "Device Type" "RESISTOR-G155-14701-01,4.7KOHMA"
			(at -0.008382 1.210564 90)
			(unlocked yes)
			(layer "B.Fab")
			(hide yes)
			(effects
				(font
					(size 0.7874 0.5842)
					(thickness 0.1524)
				)
				(justify mirror)
			)
		)
		(property "User Part Number" "PARTNUM*"
			(at -0.02032 4.024884 90)
			(unlocked yes)
			(layer "Cmts.User")
			(hide yes)
			(effects
				(font
					(size 0.7874 0.5842)
					(thickness 0.1524)
				)
				(justify mirror)
			)
		)
		(property "Tolerance" "TOL*"
			(at -0.044704 3.05435 90)
			(unlocked yes)
			(layer "Cmts.User")
			(hide yes)
			(effects
				(font
					(size 0.7874 0.5842)
					(thickness 0.1524)
				)
				(justify mirror)
			)
		)
		(duplicate_pad_numbers_are_jumpers no)
		(fp_line
			(start 1.143 -0.5588)
			(end 1.143 0.5588)
			(stroke
				(width 0.1)
				(type default)
			)
			(layer "B.SilkS")
		)
		(fp_line
			(start -1.143 -0.5588)
			(end 1.143 -0.5588)
			(stroke
				(width 0.1)
				(type default)
			)
			(layer "B.SilkS")
		)
		(fp_line
			(start 1.143 0.5588)
			(end -1.143 0.5588)
			(stroke
				(width 0.1)
				(type default)
			)
			(layer "B.SilkS")
		)
		(fp_line
			(start -1.143 0.5588)
			(end -1.143 -0.5588)
			(stroke
				(width 0.1)
				(type default)
			)
			(layer "B.SilkS")
		)
		(fp_rect
			(start 1.143 -0.5588)
			(end -1.143 0.5588)
			(stroke
				(width 0)
				(type default)
			)
			(fill no)
			(layer "B.CrtYd")
		)
		(fp_line
			(start 0.508 -0.3048)
			(end 0.508 0.3048)
			(stroke
				(width 0.1)
				(type default)
			)
			(layer "B.Fab")
		)
		(fp_line
			(start -0.508 -0.3048)
			(end 0.508 -0.3048)
			(stroke
				(width 0.1)
				(type default)
			)
			(layer "B.Fab")
		)
		(fp_line
			(start 0.508 0.3048)
			(end -0.508 0.3048)
			(stroke
				(width 0.1)
				(type default)
			)
			(layer "B.Fab")
		)
		(fp_line
			(start -0.508 0.3048)
			(end -0.508 -0.3048)
			(stroke
				(width 0.1)
				(type default)
			)
			(layer "B.Fab")
		)
		(pad "1" smd rect
			(at 0.5334 0 270)
			(size 0.7112 0.6096)
			(layers "B.Cu" "B.Mask" "B.Paste")
			(net "XP3R3V_FPGA")
		)
		(pad "2" smd rect
			(at -0.5334 0 270)
			(size 0.7112 0.6096)
			(layers "B.Cu" "B.Mask" "B.Paste")
			(net "BNO080_EVN_SDA")
		)
		(zone
			(layer "B.Cu")
			(hatch none 0.5)
			(connect_pads
				(clearance 0)
			)
			(min_thickness 0.25)
			(keepout
				(tracks allowed)
				(vias not_allowed)
				(pads allowed)
				(copperpour not_allowed)
				(footprints allowed)
			)
			(placement
				(enabled no)
				(sheetname "")
			)
			(fill
				(thermal_gap 0.5)
				(thermal_bridge_width 0.5)
				(island_removal_mode 0)
			)
			(polygon
				(pts
					(xy 88.2142 -73.3552) (xy 88.2142 -73.2028) (xy 88.8238 -73.2028) (xy 88.8238 -73.3552)
				)
			)
		)
	)
)
